(kicad_pcb
	(version 20241229)
	(generator "pcbnew")
	(generator_version "9.0")
	(general
		(thickness 1.61)
		(legacy_teardrops no)
	)
	(paper "A3")
	(title_block
		(title "RDIMM DDR5 Tester")
		(date "2026-05-21")
		(rev "2.2.0")
		(company "Antmicro")
		(comment 9 "footprints 161-165 of 796")
	)
	(layers
		(0 "F.Cu" signal)
		(4 "In1.Cu" power)
		(6 "In2.Cu" mixed)
		(8 "In3.Cu" power)
		(10 "In4.Cu" mixed)
		(12 "In5.Cu" power)
		(14 "In6.Cu" mixed)
		(16 "In7.Cu" power)
		(18 "In8.Cu" power)
		(20 "In9.Cu" mixed)
		(22 "In10.Cu" power)
		(2 "B.Cu" signal)
		(9 "F.Adhes" user "F.Adhesive")
		(11 "B.Adhes" user "B.Adhesive")
		(13 "F.Paste" user)
		(15 "B.Paste" user)
		(5 "F.SilkS" user "F.Silkscreen")
		(7 "B.SilkS" user "B.Silkscreen")
		(1 "F.Mask" user)
		(3 "B.Mask" user)
		(17 "Dwgs.User" user "User.Drawings")
		(19 "Cmts.User" user "User.Comments")
		(21 "Eco1.User" user "User.Eco1")
		(23 "Eco2.User" user "User.Eco2")
		(25 "Edge.Cuts" user)
		(27 "Margin" user)
		(31 "F.CrtYd" user "F.Courtyard")
		(29 "B.CrtYd" user "B.Courtyard")
		(35 "F.Fab" user)
		(33 "B.Fab" user)
	)
	(footprint "antmicro-footprints:C_0402_1005Metric"
		(layer "F.Cu")
		(at 241.774499 168.71 90)
		(descr "Capacitor SMD 0402")
		(tags "capacitor SMD 0402")
		(property "Reference" "C214"
			(at -3.69 0.775501 90)
			(layer "F.SilkS")
			(effects
				(font
					(size 0.7 0.7)
					(thickness 0.15)
				)
				(justify left bottom)
			)
		)
		(property "Value" "C_100n_0402"
			(at -1.022927 2.155213 90)
			(layer "F.Fab")
			(effects
				(font
					(size 0.7 0.7)
					(thickness 0.15)
				)
				(justify left bottom)
			)
		)
		(property "Datasheet" "https://www.murata.com/products/productdetail?partno=GRM155R61H104KE14%23"
			(at 0 0 90)
			(layer "F.Fab")
			(hide yes)
			(effects
				(font
					(size 1.27 1.27)
					(thickness 0.15)
				)
			)
		)
		(property "Manufacturer" "Murata"
			(at 0 0 90)
			(unlocked yes)
			(layer "F.Fab")
			(hide yes)
			(effects
				(font
					(size 1 1)
					(thickness 0.15)
				)
			)
		)
		(property "MPN" "GRM155R61H104KE14D"
			(at 0 0 90)
			(unlocked yes)
			(layer "F.Fab")
			(hide yes)
			(effects
				(font
					(size 1 1)
					(thickness 0.15)
				)
			)
		)
		(property "Val" "100n"
			(at 0 0 90)
			(unlocked yes)
			(layer "F.Fab")
			(hide yes)
			(effects
				(font
					(size 1 1)
					(thickness 0.15)
				)
			)
		)
		(property "License" "Apache-2.0"
			(at 0 0 90)
			(unlocked yes)
			(layer "F.Fab")
			(hide yes)
			(effects
				(font
					(size 1 1)
					(thickness 0.15)
				)
			)
		)
		(property "Author" "Antmicro"
			(at 0 0 90)
			(unlocked yes)
			(layer "F.Fab")
			(hide yes)
			(effects
				(font
					(size 1 1)
					(thickness 0.15)
				)
			)
		)
		(property "Voltage" "50V"
			(at 0 0 90)
			(unlocked yes)
			(layer "F.Fab")
			(hide yes)
			(effects
				(font
					(size 1 1)
					(thickness 0.15)
				)
			)
		)
		(property "Dielectric" "X5R"
			(at 0 0 90)
			(unlocked yes)
			(layer "F.Fab")
			(hide yes)
			(effects
				(font
					(size 1 1)
					(thickness 0.15)
				)
			)
		)
		(sheetname "/Supply/DC-DC AUX, MGT/")
		(sheetfile "dc-dc-aux-mgt.kicad_sch")
		(attr smd)
		(fp_rect
			(start -0.925 -0.47)
			(end 0.925 0.47)
			(stroke
				(width 0.05)
				(type default)
			)
			(fill no)
			(layer "F.CrtYd")
		)
		(fp_line
			(start 0.504 -0.25)
			(end 0.504 0.248)
			(stroke
				(width 0.15)
				(type solid)
			)
			(layer "F.Fab")
		)
		(fp_line
			(start -0.494 -0.25)
			(end 0.504 -0.25)
			(stroke
				(width 0.15)
				(type solid)
			)
			(layer "F.Fab")
		)
		(fp_line
			(start 0.504 0.248)
			(end -0.494 0.248)
			(stroke
				(width 0.15)
				(type solid)
			)
			(layer "F.Fab")
		)
		(fp_line
			(start -0.494 0.248)
			(end -0.494 -0.25)
			(stroke
				(width 0.15)
				(type solid)
			)
			(layer "F.Fab")
		)
		(fp_text user "License: Apache-2.0"
			(at -0.939 5.799 90)
			(layer "F.Fab")
			(effects
				(font
					(size 0.7 0.7)
					(thickness 0.15)
				)
				(justify left bottom)
			)
		)
		(fp_text user "${REFERENCE}"
			(at -0.939 4.599 90)
			(layer "F.Fab")
			(effects
				(font
					(size 0.7 0.7)
					(thickness 0.15)
				)
				(justify left bottom)
			)
		)
		(fp_text user "Author: Antmicro"
			(at -0.939 3.399 90)
			(layer "F.Fab")
			(effects
				(font
					(size 0.7 0.7)
					(thickness 0.15)
				)
				(justify left bottom)
			)
		)
		(pad "1" smd roundrect
			(at -0.48 0 90)
			(size 0.59 0.64)
			(layers "F.Cu" "F.Mask" "F.Paste")
			(roundrect_rratio 0.25)
			(net 38 "+3V3_AON")
			(pintype "passive")
		)
		(pad "2" smd roundrect
			(at 0.48 0 90)
			(size 0.59 0.64)
			(layers "F.Cu" "F.Mask" "F.Paste")
			(roundrect_rratio 0.25)
			(net 1 "GND")
			(pintype "passive")
		)
	)
	(footprint "antmicro-footprints:LED_0402_1005Metric_G"
		(layer "F.Cu")
		(at 107.19 114.725 180)
		(property "Reference" "D3"
			(at 0 -0.6 180)
			(unlocked yes)
			(layer "F.SilkS")
			(hide yes)
			(effects
				(font
					(size 0.7 0.7)
					(thickness 0.15)
				)
				(justify left bottom)
			)
		)
		(property "Value" "LED_G_0402_VLMTG1500-GS08"
			(at 0 1.5 180)
			(unlocked yes)
			(layer "F.Fab")
			(effects
				(font
					(size 0.7 0.7)
					(thickness 0.15)
				)
				(justify left bottom)
			)
		)
		(property "Datasheet" "https://www.vishay.com/docs/82554/vlmo1500.pdf"
			(at 0 0 180)
			(layer "F.Fab")
			(hide yes)
			(effects
				(font
					(size 1.27 1.27)
					(thickness 0.15)
				)
			)
		)
		(property "MPN" "VLMTG1500-GS08"
			(at 0 0 180)
			(unlocked yes)
			(layer "F.Fab")
			(hide yes)
			(effects
				(font
					(size 1 1)
					(thickness 0.15)
				)
			)
		)
		(property "Manufacturer" "Vishay"
			(at 0 0 180)
			(unlocked yes)
			(layer "F.Fab")
			(hide yes)
			(effects
				(font
					(size 1 1)
					(thickness 0.15)
				)
			)
		)
		(property "Color" "Green"
			(at 0 0 180)
			(unlocked yes)
			(layer "F.Fab")
			(hide yes)
			(effects
				(font
					(size 1 1)
					(thickness 0.15)
				)
			)
		)
		(property "Author" "Antmicro"
			(at 0 0 180)
			(unlocked yes)
			(layer "F.Fab")
			(hide yes)
			(effects
				(font
					(size 1 1)
					(thickness 0.15)
				)
			)
		)
		(property "License" "Apache-2.0"
			(at 0 0 180)
			(unlocked yes)
			(layer "F.Fab")
			(hide yes)
			(effects
				(font
					(size 1 1)
					(thickness 0.15)
				)
			)
		)
		(sheetname "/FPGA Config/")
		(sheetfile "fpga-config.kicad_sch")
		(attr smd)
		(fp_line
			(start -0.175 0.4)
			(end 0.175 0.4)
			(stroke
				(width 0.15)
				(type solid)
			)
			(layer "F.SilkS")
		)
		(fp_line
			(start -0.175 -0.4)
			(end 0.175 -0.4)
			(stroke
				(width 0.15)
				(type solid)
			)
			(layer "F.SilkS")
		)
		(fp_line
			(start -0.9 -0.4)
			(end -0.9 0.4)
			(stroke
				(width 0.15)
				(type solid)
			)
			(layer "F.SilkS")
		)
		(fp_rect
			(start -0.925 -0.47)
			(end 0.925 0.47)
			(stroke
				(width 0.05)
				(type default)
			)
			(fill no)
			(layer "F.CrtYd")
		)
		(fp_line
			(start 0.501 0.26)
			(end 0.501 -0.248)
			(stroke
				(width 0.15)
				(type solid)
			)
			(layer "F.Fab")
		)
		(fp_line
			(start 0.501 0.26)
			(end 0.501 -0.248)
			(stroke
				(width 0.15)
				(type solid)
			)
			(layer "F.Fab")
		)
		(fp_line
			(start 0.501 -0.248)
			(end 0.172 -0.248)
			(stroke
				(width 0.15)
				(type solid)
			)
			(layer "F.Fab")
		)
		(fp_line
			(start 0.501 -0.248)
			(end -0.489 -0.248)
			(stroke
				(width 0.15)
				(type solid)
			)
			(layer "F.Fab")
		)
		(fp_line
			(start 0.228 0.202)
			(end 0.228 0)
			(stroke
				(width 0.15)
				(type solid)
			)
			(layer "F.Fab")
		)
		(fp_line
			(start 0.228 0)
			(end 0.228 -0.202)
			(stroke
				(width 0.15)
				(type solid)
			)
			(layer "F.Fab")
		)
		(fp_line
			(start 0.228 -0.202)
			(end -0.074 0)
			(stroke
				(width 0.15)
				(type solid)
			)
			(layer "F.Fab")
		)
		(fp_line
			(start 0.172 0.26)
			(end 0.501 0.26)
			(stroke
				(width 0.15)
				(type solid)
			)
			(layer "F.Fab")
		)
		(fp_line
			(start 0.172 -0.248)
			(end 0.172 0.26)
			(stroke
				(width 0.15)
				(type solid)
			)
			(layer "F.Fab")
		)
		(fp_line
			(start -0.074 0)
			(end 0.228 0.202)
			(stroke
				(width 0.15)
				(type solid)
			)
			(layer "F.Fab")
		)
		(fp_line
			(start -0.158 0.26)
			(end -0.158 -0.248)
			(stroke
				(width 0.15)
				(type solid)
			)
			(layer "F.Fab")
		)
		(fp_line
			(start -0.158 -0.248)
			(end -0.489 -0.248)
			(stroke
				(width 0.15)
				(type solid)
			)
			(layer "F.Fab")
		)
		(fp_line
			(start -0.173 0.202)
			(end -0.173 0.102)
			(stroke
				(width 0.15)
				(type solid)
			)
			(layer "F.Fab")
		)
		(fp_line
			(start -0.173 -0.202)
			(end -0.173 0.102)
			(stroke
				(width 0.15)
				(type solid)
			)
			(layer "F.Fab")
		)
		(fp_line
			(start -0.489 0.26)
			(end 0.501 0.26)
			(stroke
				(width 0.15)
				(type solid)
			)
			(layer "F.Fab")
		)
		(fp_line
			(start -0.489 0.26)
			(end -0.158 0.26)
			(stroke
				(width 0.15)
				(type solid)
			)
			(layer "F.Fab")
		)
		(fp_line
			(start -0.489 -0.248)
			(end -0.489 0.26)
			(stroke
				(width 0.15)
				(type solid)
			)
			(layer "F.Fab")
		)
		(fp_line
			(start -0.489 -0.248)
			(end -0.489 0.26)
			(stroke
				(width 0.15)
				(type solid)
			)
			(layer "F.Fab")
		)
		(fp_text user "License: Apache-2.0"
			(at 0 5.35 180)
			(layer "F.Fab")
			(effects
				(font
					(size 0.7 0.7)
					(thickness 0.15)
				)
				(justify left bottom)
			)
		)
		(fp_text user "${REFERENCE}"
			(at 0 2.95 180)
			(unlocked yes)
			(layer "F.Fab")
			(effects
				(font
					(size 0.7 0.7)
					(thickness 0.15)
				)
				(justify left bottom)
			)
		)
		(fp_text user "Author: Antmicro"
			(at 0 4.15 180)
			(layer "F.Fab")
			(effects
				(font
					(size 0.7 0.7)
					(thickness 0.15)
				)
				(justify left bottom)
			)
		)
		(pad "1" smd roundrect
			(at -0.48 0 180)
			(size 0.59 0.64)
			(layers "F.Cu" "F.Mask" "F.Paste")
			(roundrect_rratio 0.25)
			(net 785 "Net-(D3-C)")
			(pinfunction "C")
			(pintype "passive")
		)
		(pad "2" smd roundrect
			(at 0.48 0 180)
			(size 0.59 0.64)
			(layers "F.Cu" "F.Mask" "F.Paste")
			(roundrect_rratio 0.25)
			(net 151 "+3V3")
			(pinfunction "A")
			(pintype "passive")
		)
	)
	(footprint "antmicro-footprints:MP_Pad6mm_Drill3mm"
		(layer "F.Cu")
		(at 107.5 108)
		(property "Reference" "MP1"
			(at 0 -3.2 0)
			(layer "F.SilkS")
			(hide yes)
			(effects
				(font
					(size 0.7 0.7)
					(thickness 0.15)
				)
				(justify left bottom)
			)
		)
		(property "Value" "MP_Pad6mm_Drill3mm"
			(at 0 3.9 0)
			(layer "F.Fab")
			(effects
				(font
					(size 0.7 0.7)
					(thickness 0.15)
				)
				(justify left bottom)
			)
		)
		(attr board_only exclude_from_pos_files exclude_from_bom)
		(fp_circle
			(center 0 0)
			(end 3.25 0)
			(stroke
				(width 0.05)
				(type default)
			)
			(fill no)
			(layer "F.CrtYd")
		)
		(fp_text user "${REFERENCE}"
			(at -0.178 6.025 0)
			(layer "F.Fab")
			(effects
				(font
					(size 0.7 0.7)
					(thickness 0.15)
				)
				(justify left bottom)
			)
		)
		(fp_text user "License: Apache-2.0"
			(at -0.178 8.425 0)
			(layer "F.Fab")
			(effects
				(font
					(size 0.7 0.7)
					(thickness 0.15)
				)
				(justify left bottom)
			)
		)
		(fp_text user "Author: Antmicro"
			(at -0.178 7.225 0)
			(layer "F.Fab")
			(effects
				(font
					(size 0.7 0.7)
					(thickness 0.15)
				)
				(justify left bottom)
			)
		)
		(pad "1" thru_hole circle
			(at 0 0)
			(size 6 6)
			(drill 3)
			(layers "*.Cu" "*.Mask")
			(remove_unused_layers no)
			(net 1 "GND")
		)
	)
	(footprint "antmicro-footprints:NetTie-2_SMD_Pad0.127mm"
		(layer "F.Cu")
		(at 256.063 179.78 180)
		(descr "Net tie, 2 pin, 0.127mm  SMD pads")
		(tags "net tie")
		(property "Reference" "NT12"
			(at -0.128 -1.345 0)
			(layer "F.SilkS")
			(hide yes)
			(effects
				(font
					(size 0.7 0.7)
					(thickness 0.15)
				)
				(justify right bottom)
			)
		)
		(property "Value" "Net-Tie_P0.127mm"
			(at 0 1.199 0)
			(layer "F.Fab")
			(effects
				(font
					(size 0.7 0.7)
					(thickness 0.15)
				)
				(justify right bottom)
			)
		)
		(property "MPN" ""
			(at 0 0 180)
			(unlocked yes)
			(layer "F.Fab")
			(hide yes)
			(effects
				(font
					(size 1 1)
					(thickness 0.15)
				)
			)
		)
		(property "Manufacturer" ""
			(at 0 0 180)
			(unlocked yes)
			(layer "F.Fab")
			(hide yes)
			(effects
				(font
					(size 1 1)
					(thickness 0.15)
				)
			)
		)
		(property "Author" "Antmicro"
			(at 0 0 180)
			(unlocked yes)
			(layer "F.Fab")
			(hide yes)
			(effects
				(font
					(size 1 1)
					(thickness 0.15)
				)
			)
		)
		(property "License" "Apache-2.0"
			(at 0 0 180)
			(unlocked yes)
			(layer "F.Fab")
			(hide yes)
			(effects
				(font
					(size 1 1)
					(thickness 0.15)
				)
			)
		)
		(property ki_fp_filters "Net*Tie*")
		(sheetname "/Supply/DC-DC AUX, MGT/")
		(sheetfile "dc-dc-aux-mgt.kicad_sch")
		(attr through_hole exclude_from_pos_files exclude_from_bom)
		(net_tie_pad_groups "1, 2")
		(fp_poly
			(pts
				(xy -0.0635 -0.0635) (xy 0.0625 -0.0635) (xy 0.0625 0.0635) (xy -0.0635 0.0635)
			)
			(stroke
				(width 0)
				(type solid)
			)
			(fill yes)
			(layer "F.Cu")
		)
		(fp_poly
			(pts
				(xy 0.2 -0.16) (xy 0.29 -0.07) (xy 0.29 0.07) (xy 0.2 0.16) (xy -0.2 0.16) (xy -0.29 0.07) (xy -0.29 -0.06)
				(xy -0.19 -0.16)
			)
			(stroke
				(width 0.05)
				(type solid)
			)
			(fill no)
			(layer "F.CrtYd")
		)
		(fp_text user "License: Apache-2.0"
			(at -0.128 5.6 180)
			(layer "F.Fab")
			(effects
				(font
					(size 0.7 0.7)
					(thickness 0.15)
				)
				(justify left bottom)
			)
		)
		(fp_text user "${REFERENCE}"
			(at -0.128 3.2 180)
			(layer "F.Fab")
			(effects
				(font
					(size 0.7 0.7)
					(thickness 0.15)
				)
				(justify left bottom)
			)
		)
		(fp_text user "Author: Antmicro"
			(at -0.128 4.4 180)
			(layer "F.Fab")
			(effects
				(font
					(size 0.7 0.7)
					(thickness 0.15)
				)
				(justify left bottom)
			)
		)
		(pad "1" smd roundrect
			(at -0.127 0)
			(size 0.127 0.127)
			(layers "F.Cu")
			(roundrect_rratio 0.5)
			(chamfer_ratio 0)
			(chamfer top_left bottom_left)
			(net 692 "/Supply/DC-DC AUX, MGT/MGTAVCCAUX_SEN_-")
			(pinfunction "1")
			(pintype "passive")
		)
		(pad "2" smd roundrect
			(at 0.126 0 180)
			(size 0.127 0.127)
			(layers "F.Cu")
			(roundrect_rratio 0.5)
			(chamfer_ratio 0)
			(chamfer top_left bottom_left)
			(net 573 "+1V8_MGTVCCAUX")
			(pinfunction "2")
			(pintype "passive")
		)
	)
	(footprint "antmicro-footprints:L_0402_1005Metric"
		(layer "F.Cu")
		(at 121.025 153.61 180)
		(descr "Inductor SMD 0402")
		(tags "Inductor SMD 0402")
		(property "Reference" "L8"
			(at -5.425 -0.415 0)
			(layer "F.SilkS")
			(effects
				(font
					(size 0.7 0.7)
					(thickness 0.15)
				)
				(justify right bottom)
			)
		)
		(property "Value" "L_20n_0.35A_0402"
			(at 0 1.4 0)
			(layer "F.Fab")
			(effects
				(font
					(size 0.7 0.7)
					(thickness 0.15)
				)
				(justify right bottom)
			)
		)
		(property "Datasheet" "https://product.tdk.com/system/files/dam/doc/product/inductor/inductor/smd/catalog/inductor_automotive_high-frequency_mlg1005s_en.pdf?ref_disty=mouser"
			(at 0 0 180)
			(layer "F.Fab")
			(hide yes)
			(effects
				(font
					(size 1.27 1.27)
					(thickness 0.15)
				)
			)
		)
		(property "Val" "20n/0.35A"
			(at 0 0 180)
			(unlocked yes)
			(layer "F.Fab")
			(hide yes)
			(effects
				(font
					(size 1 1)
					(thickness 0.15)
				)
			)
		)
		(property "Manufacturer" "TDK"
			(at 0 0 180)
			(unlocked yes)
			(layer "F.Fab")
			(hide yes)
			(effects
				(font
					(size 1 1)
					(thickness 0.15)
				)
			)
		)
		(property "MPN" "MLG1005S20NJTD25"
			(at 0 0 180)
			(unlocked yes)
			(layer "F.Fab")
			(hide yes)
			(effects
				(font
					(size 1 1)
					(thickness 0.15)
				)
			)
		)
		(property "ISat" ""
			(at 0 0 180)
			(unlocked yes)
			(layer "F.Fab")
			(hide yes)
			(effects
				(font
					(size 1 1)
					(thickness 0.15)
				)
			)
		)
		(property "IMax" "0.35 A"
			(at 0 0 180)
			(unlocked yes)
			(layer "F.Fab")
			(hide yes)
			(effects
				(font
					(size 1 1)
					(thickness 0.15)
				)
			)
		)
		(property "Size" "1.0x0.5"
			(at 0 0 180)
			(unlocked yes)
			(layer "F.Fab")
			(hide yes)
			(effects
				(font
					(size 1 1)
					(thickness 0.15)
				)
			)
		)
		(property "Author" "Antmicro"
			(at 0 0 180)
			(unlocked yes)
			(layer "F.Fab")
			(hide yes)
			(effects
				(font
					(size 1 1)
					(thickness 0.15)
				)
			)
		)
		(property "License" "Apache-2.0"
			(at 0 0 180)
			(unlocked yes)
			(layer "F.Fab")
			(hide yes)
			(effects
				(font
					(size 1 1)
					(thickness 0.15)
				)
			)
		)
		(sheetname "/HDMI + SD Card/")
		(sheetfile "hdmi-sd-card.kicad_sch")
		(attr smd)
		(fp_rect
			(start -0.925 -0.47)
			(end 0.925 0.47)
			(stroke
				(width 0.05)
				(type default)
			)
			(fill no)
			(layer "F.CrtYd")
		)
		(fp_rect
			(start -0.499 -0.249)
			(end 0.499 0.249)
			(stroke
				(width 0.15)
				(type solid)
			)
			(fill no)
			(layer "F.Fab")
		)
		(fp_text user "Author: Antmicro"
			(at -0.932 4.17 180)
			(layer "F.Fab")
			(effects
				(font
					(size 0.7 0.7)
					(thickness 0.15)
				)
				(justify left bottom)
			)
		)
		(fp_text user "${REFERENCE}"
			(at -0.932 3.168 180)
			(layer "F.Fab")
			(effects
				(font
					(size 0.7 0.7)
					(thickness 0.15)
				)
				(justify left bottom)
			)
		)
		(fp_text user "License: Apache-2.0"
			(at -0.932 5.17 180)
			(layer "F.Fab")
			(effects
				(font
					(size 0.7 0.7)
					(thickness 0.15)
				)
				(justify left bottom)
			)
		)
		(pad "1" smd roundrect
			(at -0.48 0 180)
			(size 0.59 0.64)
			(layers "F.Cu" "F.Mask" "F.Paste")
			(roundrect_rratio 0.25)
			(net 269 "/FPGA MGT Interface/HDMI_IN.CLK_P")
			(pintype "passive")
		)
		(pad "2" smd roundrect
			(at 0.48 0 180)
			(size 0.59 0.64)
			(layers "F.Cu" "F.Mask" "F.Paste")
			(roundrect_rratio 0.25)
			(net 678 "Net-(L8-Pad2)")
			(pintype "passive")
		)
	)
)
